# T6G (Grand Teton) — schematic netlist excerpt (pin names and nets, part order shuffled) for the footprints in the layout excerpt that follows; sources: Cadence DE-HDL packaged netlist, KiCad conversion of 04192023_DAF0TMB3IC0_F0TG_MB_C_brd_V02_OCP.brd

PC579  Q_CAP  2.2UF 10V 10% X6S  pkg C0402  page 198 : A = PVDDCR_SOC_P0_VCC1 ; B = GND
C2027  Q_CAP  0.1UF 25V 10% X7R  pkg 0402  page 236 : A = VSENSE_P3V3_INA230_1_INP ; B = VSENSE_P3V3_INA230_1_INN

(kicad_pcb
	(version 20260206)
	(generator "pcbnew")
	(generator_version "10.0")
	(general
		(thickness 1.6)
		(legacy_teardrops no)
	)
	(paper "A4")
	(title_block
		(title "04192023_DAF0TMB3IC0_F0TG_MB_C_brd_V02_OCP.brd")
		(comment 1 "Grand Teton / footprints 4126-4127 of 8354")
	)
	(layers
		(0 "F.Cu" signal "TOP")
		(4 "In1.Cu" signal "GND")
		(6 "In2.Cu" signal "IN1")
		(8 "In3.Cu" signal "GND1")
		(10 "In4.Cu" signal "IN2")
		(12 "In5.Cu" signal "GND2")
		(14 "In6.Cu" signal "IN3")
		(16 "In7.Cu" signal "GND3")
		(18 "In8.Cu" signal "VCC")
		(20 "In9.Cu" signal "VCC1")
		(22 "In10.Cu" signal "GND4")
		(24 "In11.Cu" signal "IN4")
		(26 "In12.Cu" signal "GND5")
		(28 "In13.Cu" signal "IN5")
		(30 "In14.Cu" signal "GND6")
		(32 "In15.Cu" signal "IN6")
		(34 "In16.Cu" signal "GND7")
		(2 "B.Cu" signal "BOTTOM")
		(9 "F.Adhes" user "F.Adhesive")
		(11 "B.Adhes" user "B.Adhesive")
		(13 "F.Paste" user "Package Geometry/Pastemask Top")
		(15 "B.Paste" user "Package Geometry/Pastemask Bottom")
		(5 "F.SilkS" user "Ref Des/Silkscreen Top")
		(7 "B.SilkS" user "Ref Des/Silkscreen Bottom")
		(1 "F.Mask" user "Board Geometry/Soldermask Top")
		(3 "B.Mask" user "Board Geometry/Soldermask Bottom")
		(17 "Dwgs.User" user "User.Drawings")
		(19 "Cmts.User" user "User.Comments")
		(21 "Eco1.User" user "User.Eco1")
		(23 "Eco2.User" user "User.Eco2")
		(25 "Edge.Cuts" user "Board Geometry/Outline")
		(27 "Margin" user)
		(31 "F.CrtYd" user "Package Geometry/Place Bound Top")
		(29 "B.CrtYd" user "Package Geometry/Place Bound Bottom")
		(35 "F.Fab" user "Ref Des/Assembly Top")
		(33 "B.Fab" user "Ref Des/Assembly Bottom")
	)
	(footprint ""
		(layer "F.Cu")
		(at 401.507198 -174.505874 -90)
		(property "Reference" "PC579"
			(at 0 0 270)
			(layer "F.SilkS")
			(hide yes)
			(effects
				(font
					(size 1.27 1.27)
				)
			)
		)
		(property "Value" ""
			(at 0 0 270)
			(layer "F.Fab")
			(effects
				(font
					(size 1.27 1.27)
				)
			)
		)
		(duplicate_pad_numbers_are_jumpers no)
		(fp_line
			(start -0.7874 0.4064)
			(end -0.7874 -0.4064)
			(stroke
				(width 0.1524)
				(type default)
			)
			(layer "F.SilkS")
		)
		(fp_line
			(start -0.322326 0.4064)
			(end -0.7874 0.4064)
			(stroke
				(width 0.1524)
				(type default)
			)
			(layer "F.SilkS")
		)
		(fp_line
			(start 0.7874 0.4064)
			(end 0.515874 0.4064)
			(stroke
				(width 0.1524)
				(type default)
			)
			(layer "F.SilkS")
		)
		(fp_line
			(start -0.7874 -0.4064)
			(end 0.7874 -0.4064)
			(stroke
				(width 0.1524)
				(type default)
			)
			(layer "F.SilkS")
		)
		(fp_line
			(start 0.7874 -0.4064)
			(end 0.7874 0.4064)
			(stroke
				(width 0.1524)
				(type default)
			)
			(layer "F.SilkS")
		)
		(fp_line
			(start -0.67945 0.3048)
			(end -0.67945 -0.305054)
			(stroke
				(width 0.1)
				(type default)
			)
			(layer "F.Fab")
		)
		(fp_line
			(start -0.12065 0.3048)
			(end -0.67945 0.3048)
			(stroke
				(width 0.1)
				(type default)
			)
			(layer "F.Fab")
		)
		(fp_line
			(start 0.120396 0.3048)
			(end 0.120396 0.2794)
			(stroke
				(width 0.1)
				(type default)
			)
			(layer "F.Fab")
		)
		(fp_line
			(start 0.67945 0.3048)
			(end 0.120396 0.3048)
			(stroke
				(width 0.1)
				(type default)
			)
			(layer "F.Fab")
		)
		(fp_line
			(start -0.12065 0.2794)
			(end -0.12065 0.3048)
			(stroke
				(width 0.1)
				(type default)
			)
			(layer "F.Fab")
		)
		(fp_line
			(start 0.120396 0.2794)
			(end -0.12065 0.2794)
			(stroke
				(width 0.1)
				(type default)
			)
			(layer "F.Fab")
		)
		(fp_line
			(start -0.12065 -0.2794)
			(end 0.12065 -0.2794)
			(stroke
				(width 0.1)
				(type default)
			)
			(layer "F.Fab")
		)
		(fp_line
			(start 0.12065 -0.2794)
			(end 0.12065 -0.3048)
			(stroke
				(width 0.1)
				(type default)
			)
			(layer "F.Fab")
		)
		(fp_line
			(start 0.12065 -0.3048)
			(end 0.67945 -0.3048)
			(stroke
				(width 0.1)
				(type default)
			)
			(layer "F.Fab")
		)
		(fp_line
			(start 0.67945 -0.3048)
			(end 0.67945 0.3048)
			(stroke
				(width 0.1)
				(type default)
			)
			(layer "F.Fab")
		)
		(fp_line
			(start -0.67945 -0.305054)
			(end -0.12065 -0.305054)
			(stroke
				(width 0.1)
				(type default)
			)
			(layer "F.Fab")
		)
		(fp_line
			(start -0.12065 -0.305054)
			(end -0.12065 -0.2794)
			(stroke
				(width 0.1)
				(type default)
			)
			(layer "F.Fab")
		)
		(pad "1" smd circle
			(at -0.40005 0 270)
			(size 0 0)
			(layers "F.Cu" "F.Mask" "F.Paste")
			(net "PVDDCR_SOC_P0_VCC1")
		)
		(pad "2" smd circle
			(at 0.40005 0 270)
			(size 0 0)
			(layers "F.Cu" "F.Mask" "F.Paste")
			(net "GND")
		)
	)
	(footprint ""
		(layer "F.Cu")
		(at 435.91226 -92.700348)
		(property "Reference" "C2027"
			(at 0 0 0)
			(layer "F.SilkS")
			(hide yes)
			(effects
				(font
					(size 1.27 1.27)
				)
			)
		)
		(property "Value" ""
			(at 0 0 0)
			(layer "F.Fab")
			(effects
				(font
					(size 1.27 1.27)
				)
			)
		)
		(duplicate_pad_numbers_are_jumpers no)
		(fp_line
			(start -0.7874 -0.4064)
			(end 0.7874 -0.4064)
			(stroke
				(width 0.1524)
				(type default)
			)
			(layer "F.SilkS")
		)
		(fp_line
			(start -0.7874 0.4064)
			(end -0.7874 -0.4064)
			(stroke
				(width 0.1524)
				(type default)
			)
			(layer "F.SilkS")
		)
		(fp_line
			(start 0.7874 -0.4064)
			(end 0.7874 0.4064)
			(stroke
				(width 0.1524)
				(type default)
			)
			(layer "F.SilkS")
		)
		(fp_line
			(start 0.7874 0.4064)
			(end -0.7874 0.4064)
			(stroke
				(width 0.1524)
				(type default)
			)
			(layer "F.SilkS")
		)
		(fp_line
			(start -0.67945 -0.305054)
			(end -0.12065 -0.305054)
			(stroke
				(width 0.1)
				(type default)
			)
			(layer "F.Fab")
		)
		(fp_line
			(start -0.67945 0.3048)
			(end -0.67945 -0.305054)
			(stroke
				(width 0.1)
				(type default)
			)
			(layer "F.Fab")
		)
		(fp_line
			(start -0.12065 -0.305054)
			(end -0.12065 -0.2794)
			(stroke
				(width 0.1)
				(type default)
			)
			(layer "F.Fab")
		)
		(fp_line
			(start -0.12065 -0.2794)
			(end 0.12065 -0.2794)
			(stroke
				(width 0.1)
				(type default)
			)
			(layer "F.Fab")
		)
		(fp_line
			(start -0.12065 0.2794)
			(end -0.12065 0.3048)
			(stroke
				(width 0.1)
				(type default)
			)
			(layer "F.Fab")
		)
		(fp_line
			(start -0.12065 0.3048)
			(end -0.67945 0.3048)
			(stroke
				(width 0.1)
				(type default)
			)
			(layer "F.Fab")
		)
		(fp_line
			(start 0.120396 0.2794)
			(end -0.12065 0.2794)
			(stroke
				(width 0.1)
				(type default)
			)
			(layer "F.Fab")
		)
		(fp_line
			(start 0.120396 0.3048)
			(end 0.120396 0.2794)
			(stroke
				(width 0.1)
				(type default)
			)
			(layer "F.Fab")
		)
		(fp_line
			(start 0.12065 -0.3048)
			(end 0.67945 -0.3048)
			(stroke
				(width 0.1)
				(type default)
			)
			(layer "F.Fab")
		)
		(fp_line
			(start 0.12065 -0.2794)
			(end 0.12065 -0.3048)
			(stroke
				(width 0.1)
				(type default)
			)
			(layer "F.Fab")
		)
		(fp_line
			(start 0.67945 -0.3048)
			(end 0.67945 0.3048)
			(stroke
				(width 0.1)
				(type default)
			)
			(layer "F.Fab")
		)
		(fp_line
			(start 0.67945 0.3048)
			(end 0.120396 0.3048)
			(stroke
				(width 0.1)
				(type default)
			)
			(layer "F.Fab")
		)
		(pad "1" smd circle
			(at -0.40005 0)
			(size 0 0)
			(layers "F.Cu" "F.Mask" "F.Paste")
			(net "VSENSE_P3V3_INA230_1_INP")
		)
		(pad "2" smd circle
			(at 0.40005 0)
			(size 0 0)
			(layers "F.Cu" "F.Mask" "F.Paste")
			(net "VSENSE_P3V3_INA230_1_INN")
		)
	)
)
